(kicad_pcb
	(version 20241229)
	(generator "pcbnew")
	(generator_version "9.0")
	(general
		(thickness 1.599998)
		(legacy_teardrops no)
	)
	(paper "A4")
	(title_block
		(title "Artix - Datacenter Secure Control Module (DC-SCM)")
		(date "2024-11-06")
		(rev "1.1.3")
		(comment 9 "footprints 42-46 of 544")
	)
	(layers
		(0 "F.Cu" signal)
		(4 "In1.Cu" signal)
		(6 "In2.Cu" signal)
		(8 "In3.Cu" signal)
		(10 "In4.Cu" signal)
		(12 "In5.Cu" signal)
		(14 "In6.Cu" signal)
		(2 "B.Cu" signal)
		(9 "F.Adhes" user "F.Adhesive")
		(11 "B.Adhes" user "B.Adhesive")
		(13 "F.Paste" user)
		(15 "B.Paste" user)
		(5 "F.SilkS" user "F.Silkscreen")
		(7 "B.SilkS" user "B.Silkscreen")
		(1 "F.Mask" user)
		(3 "B.Mask" user)
		(17 "Dwgs.User" user "User.Drawings")
		(19 "Cmts.User" user "User.Comments")
		(21 "Eco1.User" user "User.Eco1")
		(23 "Eco2.User" user "User.Eco2")
		(25 "Edge.Cuts" user)
		(27 "Margin" user)
		(31 "F.CrtYd" user "F.Courtyard")
		(29 "B.CrtYd" user "B.Courtyard")
		(35 "F.Fab" user)
		(33 "B.Fab" user)
	)
	(footprint "antmicro-footprints:R_0402_1005Metric"
		(layer "F.Cu")
		(at 138.625 107.06 -90)
		(descr "Resistor SMD 0402")
		(tags "resistor SMD 0402")
		(property "Reference" "R81"
			(at 0.84 -0.375 90)
			(layer "F.SilkS")
			(effects
				(font
					(size 0.7 0.7)
					(thickness 0.15)
				)
				(justify right bottom)
			)
		)
		(property "Value" "R_0R_0402"
			(at 0 1.4 90)
			(layer "F.Fab")
			(effects
				(font
					(size 0.7 0.7)
					(thickness 0.15)
				)
				(justify right bottom)
			)
		)
		(property "Datasheet" "https://industrial.panasonic.com/cdbs/www-data/pdf/RDA0000/AOA0000C301.pdf"
			(at 0 0 270)
			(layer "F.Fab")
			(hide yes)
			(effects
				(font
					(size 1.27 1.27)
					(thickness 0.15)
				)
			)
		)
		(property "Description" "SMD Chip Resistor, Jumper, 0 ohm, 100 mW, 0402 [1005 Metric], Thick Film, General Purpose"
			(at 0 0 270)
			(layer "F.Fab")
			(hide yes)
			(effects
				(font
					(size 1.27 1.27)
					(thickness 0.15)
				)
			)
		)
		(property "Author" "Antmicro"
			(at 31.565 245.685 0)
			(layer "F.Fab")
			(hide yes)
			(effects
				(font
					(size 1 1)
					(thickness 0.15)
				)
			)
		)
		(property "Current" "1A"
			(at 31.565 245.685 0)
			(layer "F.Fab")
			(hide yes)
			(effects
				(font
					(size 1 1)
					(thickness 0.15)
				)
			)
		)
		(property "License" "Apache-2.0"
			(at 31.565 245.685 0)
			(layer "F.Fab")
			(hide yes)
			(effects
				(font
					(size 1 1)
					(thickness 0.15)
				)
			)
		)
		(property "MPN" "ERJ2GE0R00X"
			(at 31.565 245.685 0)
			(layer "F.Fab")
			(hide yes)
			(effects
				(font
					(size 1 1)
					(thickness 0.15)
				)
			)
		)
		(property "Manufacturer" "Panasonic"
			(at 31.565 245.685 0)
			(layer "F.Fab")
			(hide yes)
			(effects
				(font
					(size 1 1)
					(thickness 0.15)
				)
			)
		)
		(property "Tolerance" "~"
			(at 31.565 245.685 0)
			(layer "F.Fab")
			(hide yes)
			(effects
				(font
					(size 1 1)
					(thickness 0.15)
				)
			)
		)
		(property "Val" "0R"
			(at 31.565 245.685 0)
			(layer "F.Fab")
			(hide yes)
			(effects
				(font
					(size 1 1)
					(thickness 0.15)
				)
			)
		)
		(sheetname "/FPGA banks 34-35 & CFG/")
		(sheetfile "fpga-banks-34-25-cfg.kicad_sch")
		(attr smd)
		(fp_rect
			(start -0.925 -0.47)
			(end 0.925 0.47)
			(stroke
				(width 0.05)
				(type default)
			)
			(fill no)
			(layer "F.CrtYd")
		)
		(fp_rect
			(start -0.5 -0.25)
			(end 0.5 0.25)
			(stroke
				(width 0.15)
				(type solid)
			)
			(fill no)
			(layer "F.Fab")
		)
		(pad "1" smd roundrect
			(at -0.48 0 270)
			(size 0.59 0.64)
			(layers "F.Cu" "F.Mask" "F.Paste")
			(roundrect_rratio 0.25)
			(net 2 "VCC3V3")
			(pintype "passive")
		)
		(pad "2" smd roundrect
			(at 0.48 0 270)
			(size 0.59 0.64)
			(layers "F.Cu" "F.Mask" "F.Paste")
			(roundrect_rratio 0.25)
			(net 267 "/FPGA banks 34-35 & CFG/MODE0")
			(pintype "passive")
		)
	)
	(footprint "antmicro-footprints:R_0402_1005Metric"
		(layer "F.Cu")
		(at 137.625 107.06 -90)
		(descr "Resistor SMD 0402")
		(tags "resistor SMD 0402")
		(property "Reference" "R82"
			(at 0.84 -0.375 90)
			(layer "F.SilkS")
			(effects
				(font
					(size 0.7 0.7)
					(thickness 0.15)
				)
				(justify right bottom)
			)
		)
		(property "Value" "R_0R_0402"
			(at 0 1.4 90)
			(layer "F.Fab")
			(effects
				(font
					(size 0.7 0.7)
					(thickness 0.15)
				)
				(justify right bottom)
			)
		)
		(property "Datasheet" "https://industrial.panasonic.com/cdbs/www-data/pdf/RDA0000/AOA0000C301.pdf"
			(at 0 0 270)
			(layer "F.Fab")
			(hide yes)
			(effects
				(font
					(size 1.27 1.27)
					(thickness 0.15)
				)
			)
		)
		(property "Description" "SMD Chip Resistor, Jumper, 0 ohm, 100 mW, 0402 [1005 Metric], Thick Film, General Purpose"
			(at 0 0 270)
			(layer "F.Fab")
			(hide yes)
			(effects
				(font
					(size 1.27 1.27)
					(thickness 0.15)
				)
			)
		)
		(property "Author" "Antmicro"
			(at 30.565 244.685 0)
			(layer "F.Fab")
			(hide yes)
			(effects
				(font
					(size 1 1)
					(thickness 0.15)
				)
			)
		)
		(property "Current" "1A"
			(at 30.565 244.685 0)
			(layer "F.Fab")
			(hide yes)
			(effects
				(font
					(size 1 1)
					(thickness 0.15)
				)
			)
		)
		(property "License" "Apache-2.0"
			(at 30.565 244.685 0)
			(layer "F.Fab")
			(hide yes)
			(effects
				(font
					(size 1 1)
					(thickness 0.15)
				)
			)
		)
		(property "MPN" "ERJ2GE0R00X"
			(at 30.565 244.685 0)
			(layer "F.Fab")
			(hide yes)
			(effects
				(font
					(size 1 1)
					(thickness 0.15)
				)
			)
		)
		(property "Manufacturer" "Panasonic"
			(at 30.565 244.685 0)
			(layer "F.Fab")
			(hide yes)
			(effects
				(font
					(size 1 1)
					(thickness 0.15)
				)
			)
		)
		(property "Tolerance" "~"
			(at 30.565 244.685 0)
			(layer "F.Fab")
			(hide yes)
			(effects
				(font
					(size 1 1)
					(thickness 0.15)
				)
			)
		)
		(property "Val" "0R"
			(at 30.565 244.685 0)
			(layer "F.Fab")
			(hide yes)
			(effects
				(font
					(size 1 1)
					(thickness 0.15)
				)
			)
		)
		(sheetname "/FPGA banks 34-35 & CFG/")
		(sheetfile "fpga-banks-34-25-cfg.kicad_sch")
		(attr smd exclude_from_pos_files exclude_from_bom dnp)
		(fp_rect
			(start -0.925 -0.47)
			(end 0.925 0.47)
			(stroke
				(width 0.05)
				(type default)
			)
			(fill no)
			(layer "F.CrtYd")
		)
		(fp_rect
			(start -0.5 -0.25)
			(end 0.5 0.25)
			(stroke
				(width 0.15)
				(type solid)
			)
			(fill no)
			(layer "F.Fab")
		)
		(pad "1" smd roundrect
			(at -0.48 0 270)
			(size 0.59 0.64)
			(layers "F.Cu" "F.Mask" "F.Paste")
			(roundrect_rratio 0.25)
			(net 1 "GND")
			(pintype "passive")
		)
		(pad "2" smd roundrect
			(at 0.48 0 270)
			(size 0.59 0.64)
			(layers "F.Cu" "F.Mask" "F.Paste")
			(roundrect_rratio 0.25)
			(net 267 "/FPGA banks 34-35 & CFG/MODE0")
			(pintype "passive")
		)
	)
	(footprint "antmicro-footprints:R_0402_1005Metric"
		(layer "F.Cu")
		(at 139.625 107.06 -90)
		(descr "Resistor SMD 0402")
		(tags "resistor SMD 0402")
		(property "Reference" "R83"
			(at 0.84 -0.375 90)
			(layer "F.SilkS")
			(effects
				(font
					(size 0.7 0.7)
					(thickness 0.15)
				)
				(justify right bottom)
			)
		)
		(property "Value" "R_0R_0402"
			(at 0 1.4 90)
			(layer "F.Fab")
			(effects
				(font
					(size 0.7 0.7)
					(thickness 0.15)
				)
				(justify right bottom)
			)
		)
		(property "Datasheet" "https://industrial.panasonic.com/cdbs/www-data/pdf/RDA0000/AOA0000C301.pdf"
			(at 0 0 270)
			(layer "F.Fab")
			(hide yes)
			(effects
				(font
					(size 1.27 1.27)
					(thickness 0.15)
				)
			)
		)
		(property "Description" "SMD Chip Resistor, Jumper, 0 ohm, 100 mW, 0402 [1005 Metric], Thick Film, General Purpose"
			(at 0 0 270)
			(layer "F.Fab")
			(hide yes)
			(effects
				(font
					(size 1.27 1.27)
					(thickness 0.15)
				)
			)
		)
		(property "Author" "Antmicro"
			(at 32.565 246.685 0)
			(layer "F.Fab")
			(hide yes)
			(effects
				(font
					(size 1 1)
					(thickness 0.15)
				)
			)
		)
		(property "Current" "1A"
			(at 32.565 246.685 0)
			(layer "F.Fab")
			(hide yes)
			(effects
				(font
					(size 1 1)
					(thickness 0.15)
				)
			)
		)
		(property "License" "Apache-2.0"
			(at 32.565 246.685 0)
			(layer "F.Fab")
			(hide yes)
			(effects
				(font
					(size 1 1)
					(thickness 0.15)
				)
			)
		)
		(property "MPN" "ERJ2GE0R00X"
			(at 32.565 246.685 0)
			(layer "F.Fab")
			(hide yes)
			(effects
				(font
					(size 1 1)
					(thickness 0.15)
				)
			)
		)
		(property "Manufacturer" "Panasonic"
			(at 32.565 246.685 0)
			(layer "F.Fab")
			(hide yes)
			(effects
				(font
					(size 1 1)
					(thickness 0.15)
				)
			)
		)
		(property "Tolerance" "~"
			(at 32.565 246.685 0)
			(layer "F.Fab")
			(hide yes)
			(effects
				(font
					(size 1 1)
					(thickness 0.15)
				)
			)
		)
		(property "Val" "0R"
			(at 32.565 246.685 0)
			(layer "F.Fab")
			(hide yes)
			(effects
				(font
					(size 1 1)
					(thickness 0.15)
				)
			)
		)
		(sheetname "/FPGA banks 34-35 & CFG/")
		(sheetfile "fpga-banks-34-25-cfg.kicad_sch")
		(attr smd exclude_from_pos_files exclude_from_bom dnp)
		(fp_rect
			(start -0.925 -0.47)
			(end 0.925 0.47)
			(stroke
				(width 0.05)
				(type default)
			)
			(fill no)
			(layer "F.CrtYd")
		)
		(fp_rect
			(start -0.5 -0.25)
			(end 0.5 0.25)
			(stroke
				(width 0.15)
				(type solid)
			)
			(fill no)
			(layer "F.Fab")
		)
		(pad "1" smd roundrect
			(at -0.48 0 270)
			(size 0.59 0.64)
			(layers "F.Cu" "F.Mask" "F.Paste")
			(roundrect_rratio 0.25)
			(net 2 "VCC3V3")
			(pintype "passive")
		)
		(pad "2" smd roundrect
			(at 0.48 0 270)
			(size 0.59 0.64)
			(layers "F.Cu" "F.Mask" "F.Paste")
			(roundrect_rratio 0.25)
			(net 268 "/FPGA banks 34-35 & CFG/MODE1")
			(pintype "passive")
		)
	)
	(footprint "antmicro-footprints:R_0402_1005Metric"
		(layer "F.Cu")
		(at 140.625 107.06 -90)
		(descr "Resistor SMD 0402")
		(tags "resistor SMD 0402")
		(property "Reference" "R84"
			(at 0.84 -0.375 90)
			(layer "F.SilkS")
			(effects
				(font
					(size 0.7 0.7)
					(thickness 0.15)
				)
				(justify right bottom)
			)
		)
		(property "Value" "R_0R_0402"
			(at 0 1.4 90)
			(layer "F.Fab")
			(effects
				(font
					(size 0.7 0.7)
					(thickness 0.15)
				)
				(justify right bottom)
			)
		)
		(property "Datasheet" "https://industrial.panasonic.com/cdbs/www-data/pdf/RDA0000/AOA0000C301.pdf"
			(at 0 0 270)
			(layer "F.Fab")
			(hide yes)
			(effects
				(font
					(size 1.27 1.27)
					(thickness 0.15)
				)
			)
		)
		(property "Description" "SMD Chip Resistor, Jumper, 0 ohm, 100 mW, 0402 [1005 Metric], Thick Film, General Purpose"
			(at 0 0 270)
			(layer "F.Fab")
			(hide yes)
			(effects
				(font
					(size 1.27 1.27)
					(thickness 0.15)
				)
			)
		)
		(property "Author" "Antmicro"
			(at 33.565 247.685 0)
			(layer "F.Fab")
			(hide yes)
			(effects
				(font
					(size 1 1)
					(thickness 0.15)
				)
			)
		)
		(property "Current" "1A"
			(at 33.565 247.685 0)
			(layer "F.Fab")
			(hide yes)
			(effects
				(font
					(size 1 1)
					(thickness 0.15)
				)
			)
		)
		(property "License" "Apache-2.0"
			(at 33.565 247.685 0)
			(layer "F.Fab")
			(hide yes)
			(effects
				(font
					(size 1 1)
					(thickness 0.15)
				)
			)
		)
		(property "MPN" "ERJ2GE0R00X"
			(at 33.565 247.685 0)
			(layer "F.Fab")
			(hide yes)
			(effects
				(font
					(size 1 1)
					(thickness 0.15)
				)
			)
		)
		(property "Manufacturer" "Panasonic"
			(at 33.565 247.685 0)
			(layer "F.Fab")
			(hide yes)
			(effects
				(font
					(size 1 1)
					(thickness 0.15)
				)
			)
		)
		(property "Tolerance" "~"
			(at 33.565 247.685 0)
			(layer "F.Fab")
			(hide yes)
			(effects
				(font
					(size 1 1)
					(thickness 0.15)
				)
			)
		)
		(property "Val" "0R"
			(at 33.565 247.685 0)
			(layer "F.Fab")
			(hide yes)
			(effects
				(font
					(size 1 1)
					(thickness 0.15)
				)
			)
		)
		(property "DNP" ""
			(at 0 0 270)
			(unlocked yes)
			(layer "F.Fab")
			(hide yes)
			(effects
				(font
					(size 1 1)
					(thickness 0.15)
				)
			)
		)
		(sheetname "/FPGA banks 34-35 & CFG/")
		(sheetfile "fpga-banks-34-25-cfg.kicad_sch")
		(attr smd)
		(fp_rect
			(start -0.925 -0.47)
			(end 0.925 0.47)
			(stroke
				(width 0.05)
				(type default)
			)
			(fill no)
			(layer "F.CrtYd")
		)
		(fp_rect
			(start -0.5 -0.25)
			(end 0.5 0.25)
			(stroke
				(width 0.15)
				(type solid)
			)
			(fill no)
			(layer "F.Fab")
		)
		(pad "1" smd roundrect
			(at -0.48 0 270)
			(size 0.59 0.64)
			(layers "F.Cu" "F.Mask" "F.Paste")
			(roundrect_rratio 0.25)
			(net 1 "GND")
			(pintype "passive")
		)
		(pad "2" smd roundrect
			(at 0.48 0 270)
			(size 0.59 0.64)
			(layers "F.Cu" "F.Mask" "F.Paste")
			(roundrect_rratio 0.25)
			(net 268 "/FPGA banks 34-35 & CFG/MODE1")
			(pintype "passive")
		)
	)
	(footprint "antmicro-footprints:SW_KMR211NGLFS_SMD"
		(layer "F.Cu")
		(at 65.025 92.385 -90)
		(property "Reference" "PROG_B1"
			(at -2.385 2.025 90)
			(layer "F.SilkS")
			(effects
				(font
					(size 0.7 0.7)
					(thickness 0.15)
				)
				(justify right bottom)
			)
		)
		(property "Value" "SW_KMR211NGLFS_SMD"
			(at -3 3 90)
			(layer "F.Fab")
			(effects
				(font
					(size 0.7 0.7)
					(thickness 0.15)
				)
				(justify right bottom)
			)
		)
		(property "Datasheet" "http://www.farnell.com/datasheets/2631211.pdf"
			(at 0 0 270)
			(layer "F.Fab")
			(hide yes)
			(effects
				(font
					(size 1.27 1.27)
					(thickness 0.15)
				)
			)
		)
		(property "Description" "Tactile Switch, KMR 2 Series, Top Actuated, Surface Mount, Oval Button, 120 gf, 50mA at 32VDC"
			(at 0 0 270)
			(layer "F.Fab")
			(hide yes)
			(effects
				(font
					(size 1.27 1.27)
					(thickness 0.15)
				)
			)
		)
		(property "Author" "Antmicro"
			(at -27.36 157.41 0)
			(layer "F.Fab")
			(hide yes)
			(effects
				(font
					(size 1 1)
					(thickness 0.15)
				)
			)
		)
		(property "License" "Apache-2.0"
			(at -27.36 157.41 0)
			(layer "F.Fab")
			(hide yes)
			(effects
				(font
					(size 1 1)
					(thickness 0.15)
				)
			)
		)
		(property "MPN" "KMR211NGLFS"
			(at -27.36 157.41 0)
			(layer "F.Fab")
			(hide yes)
			(effects
				(font
					(size 1 1)
					(thickness 0.15)
				)
			)
		)
		(property "Manufacturer" "C&K"
			(at -27.36 157.41 0)
			(layer "F.Fab")
			(hide yes)
			(effects
				(font
					(size 1 1)
					(thickness 0.15)
				)
			)
		)
		(sheetname "/FPGA banks 34-35 & CFG/")
		(sheetfile "fpga-banks-34-25-cfg.kicad_sch")
		(attr smd)
		(fp_line
			(start -2.1 1.601)
			(end -2.1 1.48)
			(stroke
				(width 0.15)
				(type solid)
			)
			(layer "F.SilkS")
		)
		(fp_line
			(start 2.101 1.601)
			(end -2.1 1.601)
			(stroke
				(width 0.15)
				(type solid)
			)
			(layer "F.SilkS")
		)
		(fp_line
			(start 2.101 1.601)
			(end 2.101 1.48)
			(stroke
				(width 0.15)
				(type solid)
			)
			(layer "F.SilkS")
		)
		(fp_line
			(start 2.101 -1.58)
			(end 2.101 -1.459)
			(stroke
				(width 0.15)
				(type solid)
			)
			(layer "F.SilkS")
		)
		(fp_line
			(start -2.1 -1.6)
			(end -2.1 -1.499)
			(stroke
				(width 0.15)
				(type solid)
			)
			(layer "F.SilkS")
		)
		(fp_line
			(start 2.101 -1.6)
			(end -2.1 -1.6)
			(stroke
				(width 0.15)
				(type solid)
			)
			(layer "F.SilkS")
		)
		(fp_rect
			(start 2.751 1.75)
			(end -2.748 -1.749)
			(stroke
				(width 0.05)
				(type solid)
			)
			(fill no)
			(layer "F.CrtYd")
		)
		(fp_line
			(start -2.1 1.601)
			(end 2.101 1.601)
			(stroke
				(width 0.15)
				(type solid)
			)
			(layer "F.Fab")
		)
		(fp_line
			(start 2.101 1.601)
			(end 2.101 -1.6)
			(stroke
				(width 0.15)
				(type solid)
			)
			(layer "F.Fab")
		)
		(fp_line
			(start 0.25 0.802)
			(end -0.248 0.802)
			(stroke
				(width 0.15)
				(type solid)
			)
			(layer "F.Fab")
		)
		(fp_line
			(start -0.248 -0.8)
			(end 0.25 -0.8)
			(stroke
				(width 0.15)
				(type solid)
			)
			(layer "F.Fab")
		)
		(fp_line
			(start -2.1 -1.6)
			(end -2.1 1.601)
			(stroke
				(width 0.15)
				(type solid)
			)
			(layer "F.Fab")
		)
		(fp_line
			(start 2.101 -1.6)
			(end -2.1 -1.6)
			(stroke
				(width 0.15)
				(type solid)
			)
			(layer "F.Fab")
		)
		(fp_arc
			(start -0.248 0.802)
			(mid -1.050001 0.001)
			(end -0.248 -0.8)
			(stroke
				(width 0.15)
				(type solid)
			)
			(layer "F.Fab")
		)
		(fp_arc
			(start 0.25 -0.8)
			(mid 1.051001 0.001)
			(end 0.25 0.802)
			(stroke
				(width 0.15)
				(type solid)
			)
			(layer "F.Fab")
		)
		(pad "1" smd rect
			(at -2.048 -0.8 90)
			(size 0.9 1)
			(layers "F.Cu" "F.Mask" "F.Paste")
			(net 221 "PROGRAM")
			(pinfunction "1")
			(pintype "passive")
		)
		(pad "2" smd rect
			(at 2.05 -0.8 90)
			(size 0.9 1)
			(layers "F.Cu" "F.Mask" "F.Paste")
			(net 221 "PROGRAM")
			(pinfunction "2")
			(pintype "passive")
		)
		(pad "3" smd rect
			(at -2.048 0.802 90)
			(size 0.9 1)
			(layers "F.Cu" "F.Mask" "F.Paste")
			(net 1 "GND")
			(pinfunction "3")
			(pintype "passive")
		)
		(pad "4" smd rect
			(at 2.05 0.802 90)
			(size 0.9 1)
			(layers "F.Cu" "F.Mask" "F.Paste")
			(net 1 "GND")
			(pinfunction "4")
			(pintype "passive")
		)
	)
)
